# SCM (Grand Teton) — schematic netlist excerpt (pin names and nets, part order shuffled) for the footprints in the layout excerpt that follows; sources: Cadence DE-HDL packaged netlist, KiCad conversion of 12092022_DA0F0TMDCD0_F0T_Management_Board_D_brd_V3_OCP.brd

R322  Q_RES  0 5% CHIP  pkg 0402LF  page 36 : A = PWRGD_P3V3_RGM_R1 ; B = PWRGD_P3V3_RGM
R457  Q_RES  0 5% CHIP  pkg 0402LF  page 35 : A = SMB_BMC_ALERT10_N ; B = SMB_BMC_ALERT10_R1_N

(kicad_pcb
	(version 20260206)
	(generator "pcbnew")
	(generator_version "10.0")
	(general
		(thickness 1.6)
		(legacy_teardrops no)
	)
	(paper "A4")
	(title_block
		(title "12092022_DA0F0TMDCD0_F0T_Management_Board_D_brd_V3_OCP.brd")
		(comment 1 "Grand Teton / footprints 828-829 of 1440")
	)
	(layers
		(0 "F.Cu" signal "TOP")
		(4 "In1.Cu" signal "GND")
		(6 "In2.Cu" signal "IN1")
		(8 "In3.Cu" signal "GND1")
		(10 "In4.Cu" signal "IN2")
		(12 "In5.Cu" signal "VCC")
		(14 "In6.Cu" signal "VCC1")
		(16 "In7.Cu" signal "IN3")
		(18 "In8.Cu" signal "GND2")
		(20 "In9.Cu" signal "IN4")
		(22 "In10.Cu" signal "GND3")
		(2 "B.Cu" signal "BOTTOM")
		(9 "F.Adhes" user "F.Adhesive")
		(11 "B.Adhes" user "B.Adhesive")
		(13 "F.Paste" user "Package Geometry/Pastemask Top")
		(15 "B.Paste" user "Package Geometry/Pastemask Bottom")
		(5 "F.SilkS" user "Ref Des/Silkscreen Top")
		(7 "B.SilkS" user "Ref Des/Silkscreen Bottom")
		(1 "F.Mask" user "Board Geometry/Soldermask Top")
		(3 "B.Mask" user "Board Geometry/Soldermask Bottom")
		(17 "Dwgs.User" user "User.Drawings")
		(19 "Cmts.User" user "User.Comments")
		(21 "Eco1.User" user "User.Eco1")
		(23 "Eco2.User" user "User.Eco2")
		(25 "Edge.Cuts" user "Board Geometry/Outline")
		(27 "Margin" user)
		(31 "F.CrtYd" user "Package Geometry/Place Bound Top")
		(29 "B.CrtYd" user "Package Geometry/Place Bound Bottom")
		(35 "F.Fab" user "Ref Des/Assembly Top")
		(33 "B.Fab" user "Ref Des/Assembly Bottom")
	)
	(footprint ""
		(layer "B.Cu")
		(at 12.319 -94.488 180)
		(property "Reference" "R457"
			(at 0 0 0)
			(layer "B.SilkS")
			(hide yes)
			(effects
				(font
					(size 1.27 1.27)
				)
				(justify mirror)
			)
		)
		(property "Value" ""
			(at 0 0 0)
			(layer "B.Fab")
			(effects
				(font
					(size 1.27 1.27)
				)
				(justify mirror)
			)
		)
		(duplicate_pad_numbers_are_jumpers no)
		(fp_line
			(start 0.7874 0.4064)
			(end 0.7874 -0.4064)
			(stroke
				(width 0.1524)
				(type default)
			)
			(layer "B.SilkS")
		)
		(fp_line
			(start 0.7874 -0.4064)
			(end -0.7874 -0.4064)
			(stroke
				(width 0.1524)
				(type default)
			)
			(layer "B.SilkS")
		)
		(fp_line
			(start -0.7874 0.4064)
			(end 0.7874 0.4064)
			(stroke
				(width 0.1524)
				(type default)
			)
			(layer "B.SilkS")
		)
		(fp_line
			(start -0.7874 -0.4064)
			(end -0.7874 0.4064)
			(stroke
				(width 0.1524)
				(type default)
			)
			(layer "B.SilkS")
		)
		(fp_line
			(start 0.67945 0.3048)
			(end 0.67945 -0.305054)
			(stroke
				(width 0.1)
				(type default)
			)
			(layer "B.Fab")
		)
		(fp_line
			(start 0.67945 -0.305054)
			(end 0.12065 -0.305054)
			(stroke
				(width 0.1)
				(type default)
			)
			(layer "B.Fab")
		)
		(fp_line
			(start 0.12065 0.3048)
			(end 0.67945 0.3048)
			(stroke
				(width 0.1)
				(type default)
			)
			(layer "B.Fab")
		)
		(fp_line
			(start 0.12065 0.2794)
			(end 0.12065 0.3048)
			(stroke
				(width 0.1)
				(type default)
			)
			(layer "B.Fab")
		)
		(fp_line
			(start 0.12065 -0.2794)
			(end -0.12065 -0.2794)
			(stroke
				(width 0.1)
				(type default)
			)
			(layer "B.Fab")
		)
		(fp_line
			(start 0.12065 -0.305054)
			(end 0.12065 -0.2794)
			(stroke
				(width 0.1)
				(type default)
			)
			(layer "B.Fab")
		)
		(fp_line
			(start -0.120396 0.3048)
			(end -0.120396 0.2794)
			(stroke
				(width 0.1)
				(type default)
			)
			(layer "B.Fab")
		)
		(fp_line
			(start -0.120396 0.2794)
			(end 0.12065 0.2794)
			(stroke
				(width 0.1)
				(type default)
			)
			(layer "B.Fab")
		)
		(fp_line
			(start -0.12065 -0.2794)
			(end -0.12065 -0.3048)
			(stroke
				(width 0.1)
				(type default)
			)
			(layer "B.Fab")
		)
		(fp_line
			(start -0.12065 -0.3048)
			(end -0.67945 -0.3048)
			(stroke
				(width 0.1)
				(type default)
			)
			(layer "B.Fab")
		)
		(fp_line
			(start -0.67945 0.3048)
			(end -0.120396 0.3048)
			(stroke
				(width 0.1)
				(type default)
			)
			(layer "B.Fab")
		)
		(fp_line
			(start -0.67945 -0.3048)
			(end -0.67945 0.3048)
			(stroke
				(width 0.1)
				(type default)
			)
			(layer "B.Fab")
		)
		(pad "1" smd circle
			(at 0.40005 0)
			(size 0 0)
			(layers "B.Cu" "B.Mask" "B.Paste")
			(net "SMB_BMC_ALERT10_N")
		)
		(pad "2" smd circle
			(at -0.40005 0)
			(size 0 0)
			(layers "B.Cu" "B.Mask" "B.Paste")
			(net "SMB_BMC_ALERT10_R1_N")
		)
	)
	(footprint ""
		(layer "B.Cu")
		(at 18.923 -101.981 -90)
		(property "Reference" "R322"
			(at 0 0 90)
			(layer "B.SilkS")
			(hide yes)
			(effects
				(font
					(size 1.27 1.27)
				)
				(justify mirror)
			)
		)
		(property "Value" ""
			(at 0 0 90)
			(layer "B.Fab")
			(effects
				(font
					(size 1.27 1.27)
				)
				(justify mirror)
			)
		)
		(duplicate_pad_numbers_are_jumpers no)
		(fp_line
			(start -0.7874 0.4064)
			(end 0.7874 0.4064)
			(stroke
				(width 0.1524)
				(type default)
			)
			(layer "B.SilkS")
		)
		(fp_line
			(start 0.7874 0.4064)
			(end 0.7874 -0.4064)
			(stroke
				(width 0.1524)
				(type default)
			)
			(layer "B.SilkS")
		)
		(fp_line
			(start -0.7874 -0.4064)
			(end -0.7874 0.4064)
			(stroke
				(width 0.1524)
				(type default)
			)
			(layer "B.SilkS")
		)
		(fp_line
			(start 0.7874 -0.4064)
			(end -0.7874 -0.4064)
			(stroke
				(width 0.1524)
				(type default)
			)
			(layer "B.SilkS")
		)
		(fp_line
			(start -0.67945 0.3048)
			(end -0.120396 0.3048)
			(stroke
				(width 0.1)
				(type default)
			)
			(layer "B.Fab")
		)
		(fp_line
			(start -0.120396 0.3048)
			(end -0.120396 0.2794)
			(stroke
				(width 0.1)
				(type default)
			)
			(layer "B.Fab")
		)
		(fp_line
			(start 0.12065 0.3048)
			(end 0.67945 0.3048)
			(stroke
				(width 0.1)
				(type default)
			)
			(layer "B.Fab")
		)
		(fp_line
			(start 0.67945 0.3048)
			(end 0.67945 -0.305054)
			(stroke
				(width 0.1)
				(type default)
			)
			(layer "B.Fab")
		)
		(fp_line
			(start -0.120396 0.2794)
			(end 0.12065 0.2794)
			(stroke
				(width 0.1)
				(type default)
			)
			(layer "B.Fab")
		)
		(fp_line
			(start 0.12065 0.2794)
			(end 0.12065 0.3048)
			(stroke
				(width 0.1)
				(type default)
			)
			(layer "B.Fab")
		)
		(fp_line
			(start -0.12065 -0.2794)
			(end -0.12065 -0.3048)
			(stroke
				(width 0.1)
				(type default)
			)
			(layer "B.Fab")
		)
		(fp_line
			(start 0.12065 -0.2794)
			(end -0.12065 -0.2794)
			(stroke
				(width 0.1)
				(type default)
			)
			(layer "B.Fab")
		)
		(fp_line
			(start -0.67945 -0.3048)
			(end -0.67945 0.3048)
			(stroke
				(width 0.1)
				(type default)
			)
			(layer "B.Fab")
		)
		(fp_line
			(start -0.12065 -0.3048)
			(end -0.67945 -0.3048)
			(stroke
				(width 0.1)
				(type default)
			)
			(layer "B.Fab")
		)
		(fp_line
			(start 0.12065 -0.305054)
			(end 0.12065 -0.2794)
			(stroke
				(width 0.1)
				(type default)
			)
			(layer "B.Fab")
		)
		(fp_line
			(start 0.67945 -0.305054)
			(end 0.12065 -0.305054)
			(stroke
				(width 0.1)
				(type default)
			)
			(layer "B.Fab")
		)
		(pad "1" smd circle
			(at 0.40005 0 90)
			(size 0 0)
			(layers "B.Cu" "B.Mask" "B.Paste")
			(net "PWRGD_P3V3_RGM_R1")
		)
		(pad "2" smd circle
			(at -0.40005 0 90)
			(size 0 0)
			(layers "B.Cu" "B.Mask" "B.Paste")
			(net "PWRGD_P3V3_RGM")
		)
	)
)
